(kicad_pcb
	(version 20260206)
	(generator "pcbnew")
	(generator_version "10.0")
	(general
		(thickness 1.6)
		(legacy_teardrops no)
	)
	(paper "A4")
	(title_block
		(title "03242023_DA0F0TMBIJ0_F0T_Motherboard_J_brd_V01_OCP.brd")
		(comment 1 "Grand Teton / footprints 1604-1606 of 6105")
	)
	(layers
		(0 "F.Cu" signal "TOP")
		(4 "In1.Cu" signal "GND")
		(6 "In2.Cu" signal "IN1")
		(8 "In3.Cu" signal "GND1")
		(10 "In4.Cu" signal "IN2")
		(12 "In5.Cu" signal "GND2")
		(14 "In6.Cu" signal "IN3")
		(16 "In7.Cu" signal "GND3")
		(18 "In8.Cu" signal "VCC")
		(20 "In9.Cu" signal "VCC1")
		(22 "In10.Cu" signal "GND4")
		(24 "In11.Cu" signal "IN4")
		(26 "In12.Cu" signal "GND5")
		(28 "In13.Cu" signal "IN5")
		(30 "In14.Cu" signal "GND6")
		(32 "In15.Cu" signal "IN6")
		(34 "In16.Cu" signal "GND7")
		(2 "B.Cu" signal "BOTTOM")
		(9 "F.Adhes" user "F.Adhesive")
		(11 "B.Adhes" user "B.Adhesive")
		(13 "F.Paste" user "Package Geometry/Pastemask Top")
		(15 "B.Paste" user "Package Geometry/Pastemask Bottom")
		(5 "F.SilkS" user "Ref Des/Silkscreen Top")
		(7 "B.SilkS" user "Ref Des/Silkscreen Bottom")
		(1 "F.Mask" user "Board Geometry/Soldermask Top")
		(3 "B.Mask" user "Board Geometry/Soldermask Bottom")
		(17 "Dwgs.User" user "User.Drawings")
		(19 "Cmts.User" user "User.Comments")
		(21 "Eco1.User" user "User.Eco1")
		(23 "Eco2.User" user "User.Eco2")
		(25 "Edge.Cuts" user "Board Geometry/Outline")
		(27 "Margin" user)
		(31 "F.CrtYd" user "Package Geometry/Place Bound Top")
		(29 "B.CrtYd" user "Package Geometry/Place Bound Bottom")
		(35 "F.Fab" user "Ref Des/Assembly Top")
		(33 "B.Fab" user "Ref Des/Assembly Bottom")
	)
	(footprint ""
		(layer "F.Cu")
		(at 77.128878 -23.308818 180)
		(property "Reference" "PC2098"
			(at 0 0 180)
			(layer "F.SilkS")
			(hide yes)
			(effects
				(font
					(size 1.27 1.27)
				)
			)
		)
		(property "Value" ""
			(at 0 0 180)
			(layer "F.Fab")
			(effects
				(font
					(size 1.27 1.27)
				)
			)
		)
		(duplicate_pad_numbers_are_jumpers no)
		(fp_line
			(start 0.7874 0.4064)
			(end -0.7874 0.4064)
			(stroke
				(width 0.1524)
				(type default)
			)
			(layer "F.SilkS")
		)
		(fp_line
			(start 0.7874 -0.4064)
			(end 0.7874 0.4064)
			(stroke
				(width 0.1524)
				(type default)
			)
			(layer "F.SilkS")
		)
		(fp_line
			(start -0.7874 0.4064)
			(end -0.7874 -0.4064)
			(stroke
				(width 0.1524)
				(type default)
			)
			(layer "F.SilkS")
		)
		(fp_line
			(start -0.7874 -0.4064)
			(end 0.7874 -0.4064)
			(stroke
				(width 0.1524)
				(type default)
			)
			(layer "F.SilkS")
		)
		(fp_line
			(start 0.67945 0.3048)
			(end 0.120396 0.3048)
			(stroke
				(width 0.1)
				(type default)
			)
			(layer "F.Fab")
		)
		(fp_line
			(start 0.67945 -0.3048)
			(end 0.67945 0.3048)
			(stroke
				(width 0.1)
				(type default)
			)
			(layer "F.Fab")
		)
		(fp_line
			(start 0.12065 -0.2794)
			(end 0.12065 -0.3048)
			(stroke
				(width 0.1)
				(type default)
			)
			(layer "F.Fab")
		)
		(fp_line
			(start 0.12065 -0.3048)
			(end 0.67945 -0.3048)
			(stroke
				(width 0.1)
				(type default)
			)
			(layer "F.Fab")
		)
		(fp_line
			(start 0.120396 0.3048)
			(end 0.120396 0.2794)
			(stroke
				(width 0.1)
				(type default)
			)
			(layer "F.Fab")
		)
		(fp_line
			(start 0.120396 0.2794)
			(end -0.12065 0.2794)
			(stroke
				(width 0.1)
				(type default)
			)
			(layer "F.Fab")
		)
		(fp_line
			(start -0.12065 0.3048)
			(end -0.67945 0.3048)
			(stroke
				(width 0.1)
				(type default)
			)
			(layer "F.Fab")
		)
		(fp_line
			(start -0.12065 0.2794)
			(end -0.12065 0.3048)
			(stroke
				(width 0.1)
				(type default)
			)
			(layer "F.Fab")
		)
		(fp_line
			(start -0.12065 -0.2794)
			(end 0.12065 -0.2794)
			(stroke
				(width 0.1)
				(type default)
			)
			(layer "F.Fab")
		)
		(fp_line
			(start -0.12065 -0.305054)
			(end -0.12065 -0.2794)
			(stroke
				(width 0.1)
				(type default)
			)
			(layer "F.Fab")
		)
		(fp_line
			(start -0.67945 0.3048)
			(end -0.67945 -0.305054)
			(stroke
				(width 0.1)
				(type default)
			)
			(layer "F.Fab")
		)
		(fp_line
			(start -0.67945 -0.305054)
			(end -0.12065 -0.305054)
			(stroke
				(width 0.1)
				(type default)
			)
			(layer "F.Fab")
		)
		(pad "1" smd circle
			(at -0.40005 0 180)
			(size 0 0)
			(layers "F.Cu" "F.Mask" "F.Paste")
			(net "P12V_OCP_VCC_2")
		)
		(pad "2" smd circle
			(at 0.40005 0 180)
			(size 0 0)
			(layers "F.Cu" "F.Mask" "F.Paste")
			(net "GND")
		)
	)
	(footprint ""
		(layer "F.Cu")
		(at 70.93712 -53.543708)
		(property "Reference" "PR3855"
			(at 0 0 0)
			(layer "F.SilkS")
			(hide yes)
			(effects
				(font
					(size 1.27 1.27)
				)
			)
		)
		(property "Value" ""
			(at 0 0 0)
			(layer "F.Fab")
			(effects
				(font
					(size 1.27 1.27)
				)
			)
		)
		(duplicate_pad_numbers_are_jumpers no)
		(fp_line
			(start -0.7874 -0.4064)
			(end 0.7874 -0.4064)
			(stroke
				(width 0.1524)
				(type default)
			)
			(layer "F.SilkS")
		)
		(fp_line
			(start -0.7874 0.4064)
			(end -0.7874 -0.4064)
			(stroke
				(width 0.1524)
				(type default)
			)
			(layer "F.SilkS")
		)
		(fp_line
			(start 0.7874 -0.4064)
			(end 0.7874 0.4064)
			(stroke
				(width 0.1524)
				(type default)
			)
			(layer "F.SilkS")
		)
		(fp_line
			(start 0.7874 0.4064)
			(end -0.7874 0.4064)
			(stroke
				(width 0.1524)
				(type default)
			)
			(layer "F.SilkS")
		)
		(fp_line
			(start -0.67945 -0.305054)
			(end -0.12065 -0.305054)
			(stroke
				(width 0.1)
				(type default)
			)
			(layer "F.Fab")
		)
		(fp_line
			(start -0.67945 0.3048)
			(end -0.67945 -0.305054)
			(stroke
				(width 0.1)
				(type default)
			)
			(layer "F.Fab")
		)
		(fp_line
			(start -0.12065 -0.305054)
			(end -0.12065 -0.2794)
			(stroke
				(width 0.1)
				(type default)
			)
			(layer "F.Fab")
		)
		(fp_line
			(start -0.12065 -0.2794)
			(end 0.12065 -0.2794)
			(stroke
				(width 0.1)
				(type default)
			)
			(layer "F.Fab")
		)
		(fp_line
			(start -0.12065 0.2794)
			(end -0.12065 0.3048)
			(stroke
				(width 0.1)
				(type default)
			)
			(layer "F.Fab")
		)
		(fp_line
			(start -0.12065 0.3048)
			(end -0.67945 0.3048)
			(stroke
				(width 0.1)
				(type default)
			)
			(layer "F.Fab")
		)
		(fp_line
			(start 0.120396 0.2794)
			(end -0.12065 0.2794)
			(stroke
				(width 0.1)
				(type default)
			)
			(layer "F.Fab")
		)
		(fp_line
			(start 0.120396 0.3048)
			(end 0.120396 0.2794)
			(stroke
				(width 0.1)
				(type default)
			)
			(layer "F.Fab")
		)
		(fp_line
			(start 0.12065 -0.3048)
			(end 0.67945 -0.3048)
			(stroke
				(width 0.1)
				(type default)
			)
			(layer "F.Fab")
		)
		(fp_line
			(start 0.12065 -0.2794)
			(end 0.12065 -0.3048)
			(stroke
				(width 0.1)
				(type default)
			)
			(layer "F.Fab")
		)
		(fp_line
			(start 0.67945 -0.3048)
			(end 0.67945 0.3048)
			(stroke
				(width 0.1)
				(type default)
			)
			(layer "F.Fab")
		)
		(fp_line
			(start 0.67945 0.3048)
			(end 0.120396 0.3048)
			(stroke
				(width 0.1)
				(type default)
			)
			(layer "F.Fab")
		)
		(pad "1" smd circle
			(at -0.40005 0)
			(size 0 0)
			(layers "F.Cu" "F.Mask" "F.Paste")
			(net "P3V3_OCP_MODE_2")
		)
		(pad "2" smd circle
			(at 0.40005 0)
			(size 0 0)
			(layers "F.Cu" "F.Mask" "F.Paste")
			(net "GND")
		)
	)
	(footprint ""
		(layer "F.Cu")
		(at 120.438926 -122.096784 90)
		(property "Reference" "R933"
			(at 0 0 90)
			(layer "F.SilkS")
			(hide yes)
			(effects
				(font
					(size 1.27 1.27)
				)
			)
		)
		(property "Value" ""
			(at 0 0 90)
			(layer "F.Fab")
			(effects
				(font
					(size 1.27 1.27)
				)
			)
		)
		(duplicate_pad_numbers_are_jumpers no)
		(fp_line
			(start 0.7874 -0.4064)
			(end 0.7874 0.4064)
			(stroke
				(width 0.1524)
				(type default)
			)
			(layer "F.SilkS")
		)
		(fp_line
			(start -0.7874 -0.4064)
			(end 0.7874 -0.4064)
			(stroke
				(width 0.1524)
				(type default)
			)
			(layer "F.SilkS")
		)
		(fp_line
			(start 0.7874 0.4064)
			(end -0.7874 0.4064)
			(stroke
				(width 0.1524)
				(type default)
			)
			(layer "F.SilkS")
		)
		(fp_line
			(start -0.7874 0.4064)
			(end -0.7874 -0.4064)
			(stroke
				(width 0.1524)
				(type default)
			)
			(layer "F.SilkS")
		)
		(fp_line
			(start -0.12065 -0.305054)
			(end -0.12065 -0.2794)
			(stroke
				(width 0.1)
				(type default)
			)
			(layer "F.Fab")
		)
		(fp_line
			(start -0.67945 -0.305054)
			(end -0.12065 -0.305054)
			(stroke
				(width 0.1)
				(type default)
			)
			(layer "F.Fab")
		)
		(fp_line
			(start 0.67945 -0.3048)
			(end 0.67945 0.3048)
			(stroke
				(width 0.1)
				(type default)
			)
			(layer "F.Fab")
		)
		(fp_line
			(start 0.12065 -0.3048)
			(end 0.67945 -0.3048)
			(stroke
				(width 0.1)
				(type default)
			)
			(layer "F.Fab")
		)
		(fp_line
			(start 0.12065 -0.2794)
			(end 0.12065 -0.3048)
			(stroke
				(width 0.1)
				(type default)
			)
			(layer "F.Fab")
		)
		(fp_line
			(start -0.12065 -0.2794)
			(end 0.12065 -0.2794)
			(stroke
				(width 0.1)
				(type default)
			)
			(layer "F.Fab")
		)
		(fp_line
			(start 0.120396 0.2794)
			(end -0.12065 0.2794)
			(stroke
				(width 0.1)
				(type default)
			)
			(layer "F.Fab")
		)
		(fp_line
			(start -0.12065 0.2794)
			(end -0.12065 0.3048)
			(stroke
				(width 0.1)
				(type default)
			)
			(layer "F.Fab")
		)
		(fp_line
			(start 0.67945 0.3048)
			(end 0.120396 0.3048)
			(stroke
				(width 0.1)
				(type default)
			)
			(layer "F.Fab")
		)
		(fp_line
			(start 0.120396 0.3048)
			(end 0.120396 0.2794)
			(stroke
				(width 0.1)
				(type default)
			)
			(layer "F.Fab")
		)
		(fp_line
			(start -0.12065 0.3048)
			(end -0.67945 0.3048)
			(stroke
				(width 0.1)
				(type default)
			)
			(layer "F.Fab")
		)
		(fp_line
			(start -0.67945 0.3048)
			(end -0.67945 -0.305054)
			(stroke
				(width 0.1)
				(type default)
			)
			(layer "F.Fab")
		)
		(pad "1" smd circle
			(at -0.40005 0 90)
			(size 0 0)
			(layers "F.Cu" "F.Mask" "F.Paste")
			(net "RST_CPU1_DRAM_AB_N")
		)
		(pad "2" smd circle
			(at 0.40005 0 90)
			(size 0 0)
			(layers "F.Cu" "F.Mask" "F.Paste")
			(net "GND")
		)
	)
)
